(kicad_pcb
	(version 20260206)
	(generator "pcbnew")
	(generator_version "10.0")
	(general
		(thickness 1.6)
		(legacy_teardrops no)
	)
	(paper "A4")
	(title_block
		(title "04192023_DAF0TMB3IC0_F0TG_MB_C_brd_V02_OCP.brd")
		(comment 1 "Grand Teton / footprints 2896-2903 of 8354")
	)
	(layers
		(0 "F.Cu" signal "TOP")
		(4 "In1.Cu" signal "GND")
		(6 "In2.Cu" signal "IN1")
		(8 "In3.Cu" signal "GND1")
		(10 "In4.Cu" signal "IN2")
		(12 "In5.Cu" signal "GND2")
		(14 "In6.Cu" signal "IN3")
		(16 "In7.Cu" signal "GND3")
		(18 "In8.Cu" signal "VCC")
		(20 "In9.Cu" signal "VCC1")
		(22 "In10.Cu" signal "GND4")
		(24 "In11.Cu" signal "IN4")
		(26 "In12.Cu" signal "GND5")
		(28 "In13.Cu" signal "IN5")
		(30 "In14.Cu" signal "GND6")
		(32 "In15.Cu" signal "IN6")
		(34 "In16.Cu" signal "GND7")
		(2 "B.Cu" signal "BOTTOM")
		(9 "F.Adhes" user "F.Adhesive")
		(11 "B.Adhes" user "B.Adhesive")
		(13 "F.Paste" user "Package Geometry/Pastemask Top")
		(15 "B.Paste" user "Package Geometry/Pastemask Bottom")
		(5 "F.SilkS" user "Ref Des/Silkscreen Top")
		(7 "B.SilkS" user "Ref Des/Silkscreen Bottom")
		(1 "F.Mask" user "Board Geometry/Soldermask Top")
		(3 "B.Mask" user "Board Geometry/Soldermask Bottom")
		(17 "Dwgs.User" user "User.Drawings")
		(19 "Cmts.User" user "User.Comments")
		(21 "Eco1.User" user "User.Eco1")
		(23 "Eco2.User" user "User.Eco2")
		(25 "Edge.Cuts" user "Board Geometry/Outline")
		(27 "Margin" user)
		(31 "F.CrtYd" user "Package Geometry/Place Bound Top")
		(29 "B.CrtYd" user "Package Geometry/Place Bound Bottom")
		(35 "F.Fab" user "Ref Des/Assembly Top")
		(33 "B.Fab" user "Ref Des/Assembly Bottom")
	)
	(footprint ""
		(layer "F.Cu")
		(at 249.28703 -45.995082 90)
		(property "Reference" "PR3962"
			(at 0 0 90)
			(layer "F.SilkS")
			(hide yes)
			(effects
				(font
					(size 1.27 1.27)
				)
			)
		)
		(property "Value" ""
			(at 0 0 90)
			(layer "F.Fab")
			(effects
				(font
					(size 1.27 1.27)
				)
			)
		)
		(duplicate_pad_numbers_are_jumpers no)
		(fp_line
			(start 0.7874 -0.4064)
			(end 0.7874 0.4064)
			(stroke
				(width 0.1524)
				(type default)
			)
			(layer "F.SilkS")
		)
		(fp_line
			(start -0.7874 -0.4064)
			(end 0.7874 -0.4064)
			(stroke
				(width 0.1524)
				(type default)
			)
			(layer "F.SilkS")
		)
		(fp_line
			(start 0.7874 0.4064)
			(end -0.7874 0.4064)
			(stroke
				(width 0.1524)
				(type default)
			)
			(layer "F.SilkS")
		)
		(fp_line
			(start -0.7874 0.4064)
			(end -0.7874 -0.4064)
			(stroke
				(width 0.1524)
				(type default)
			)
			(layer "F.SilkS")
		)
		(fp_line
			(start -0.12065 -0.305054)
			(end -0.12065 -0.2794)
			(stroke
				(width 0.1)
				(type default)
			)
			(layer "F.Fab")
		)
		(fp_line
			(start -0.67945 -0.305054)
			(end -0.12065 -0.305054)
			(stroke
				(width 0.1)
				(type default)
			)
			(layer "F.Fab")
		)
		(fp_line
			(start 0.67945 -0.3048)
			(end 0.67945 0.3048)
			(stroke
				(width 0.1)
				(type default)
			)
			(layer "F.Fab")
		)
		(fp_line
			(start 0.12065 -0.3048)
			(end 0.67945 -0.3048)
			(stroke
				(width 0.1)
				(type default)
			)
			(layer "F.Fab")
		)
		(fp_line
			(start 0.12065 -0.2794)
			(end 0.12065 -0.3048)
			(stroke
				(width 0.1)
				(type default)
			)
			(layer "F.Fab")
		)
		(fp_line
			(start -0.12065 -0.2794)
			(end 0.12065 -0.2794)
			(stroke
				(width 0.1)
				(type default)
			)
			(layer "F.Fab")
		)
		(fp_line
			(start 0.120396 0.2794)
			(end -0.12065 0.2794)
			(stroke
				(width 0.1)
				(type default)
			)
			(layer "F.Fab")
		)
		(fp_line
			(start -0.12065 0.2794)
			(end -0.12065 0.3048)
			(stroke
				(width 0.1)
				(type default)
			)
			(layer "F.Fab")
		)
		(fp_line
			(start 0.67945 0.3048)
			(end 0.120396 0.3048)
			(stroke
				(width 0.1)
				(type default)
			)
			(layer "F.Fab")
		)
		(fp_line
			(start 0.120396 0.3048)
			(end 0.120396 0.2794)
			(stroke
				(width 0.1)
				(type default)
			)
			(layer "F.Fab")
		)
		(fp_line
			(start -0.12065 0.3048)
			(end -0.67945 0.3048)
			(stroke
				(width 0.1)
				(type default)
			)
			(layer "F.Fab")
		)
		(fp_line
			(start -0.67945 0.3048)
			(end -0.67945 -0.305054)
			(stroke
				(width 0.1)
				(type default)
			)
			(layer "F.Fab")
		)
		(pad "1" smd circle
			(at -0.40005 0 90)
			(size 0 0)
			(layers "F.Cu" "F.Mask" "F.Paste")
			(net "P12V_E1S_OV_0")
		)
		(pad "2" smd circle
			(at 0.40005 0 90)
			(size 0 0)
			(layers "F.Cu" "F.Mask" "F.Paste")
			(net "GND")
		)
	)
	(footprint ""
		(layer "F.Cu")
		(at 334.400906 -416.899344 -90)
		(property "Reference" "C6522"
			(at 0 0 270)
			(layer "F.SilkS")
			(hide yes)
			(effects
				(font
					(size 1.27 1.27)
				)
			)
		)
		(property "Value" ""
			(at 0 0 270)
			(layer "F.Fab")
			(effects
				(font
					(size 1.27 1.27)
				)
			)
		)
		(duplicate_pad_numbers_are_jumpers no)
		(fp_line
			(start -0.299974 0.150114)
			(end -0.299974 -0.150114)
			(stroke
				(width 0.1)
				(type default)
			)
			(layer "F.Fab")
		)
		(fp_line
			(start 0.299974 0.150114)
			(end -0.299974 0.150114)
			(stroke
				(width 0.1)
				(type default)
			)
			(layer "F.Fab")
		)
		(fp_line
			(start -0.299974 -0.150114)
			(end 0.299974 -0.150114)
			(stroke
				(width 0.1)
				(type default)
			)
			(layer "F.Fab")
		)
		(fp_line
			(start 0.299974 -0.150114)
			(end 0.299974 0.150114)
			(stroke
				(width 0.1)
				(type default)
			)
			(layer "F.Fab")
		)
		(pad "1" smd rect
			(at -0.2667 0 270)
			(size 0.3048 0.381)
			(layers "F.Cu" "F.Mask" "F.Paste")
			(net "P5E_CPU0_P0_TX_BUF_C_DN<10>")
		)
		(pad "2" smd rect
			(at 0.2667 0 270)
			(size 0.3048 0.381)
			(layers "F.Cu" "F.Mask" "F.Paste")
			(net "P5E_CPU0_P0_TX_BUF_DN<10>")
		)
	)
	(footprint ""
		(layer "F.Cu")
		(at 10.339832 -347.702632)
		(property "Reference" "H102"
			(at -4.555998 -5.990336 0)
			(unlocked yes)
			(layer "F.SilkS")
			(effects
				(font
					(size 0.7874 0.5842)
					(thickness 0.1524)
				)
				(justify left)
			)
		)
		(property "Value" ""
			(at 0 0 0)
			(layer "F.Fab")
			(effects
				(font
					(size 1.27 1.27)
				)
			)
		)
		(duplicate_pad_numbers_are_jumpers no)
		(pad "1" thru_hole circle
			(at 0 0)
			(size 10.0076 10.0076)
			(drill 5.6134)
			(layers "*.Cu" "*.Mask")
			(remove_unused_layers no)
			(net "GND")
			(clearance -1.9431)
		)
	)
	(footprint ""
		(layer "F.Cu")
		(at 349.717106 -416.899344 -90)
		(property "Reference" "C6532"
			(at 0 0 270)
			(layer "F.SilkS")
			(hide yes)
			(effects
				(font
					(size 1.27 1.27)
				)
			)
		)
		(property "Value" ""
			(at 0 0 270)
			(layer "F.Fab")
			(effects
				(font
					(size 1.27 1.27)
				)
			)
		)
		(duplicate_pad_numbers_are_jumpers no)
		(fp_line
			(start -0.299974 0.150114)
			(end -0.299974 -0.150114)
			(stroke
				(width 0.1)
				(type default)
			)
			(layer "F.Fab")
		)
		(fp_line
			(start 0.299974 0.150114)
			(end -0.299974 0.150114)
			(stroke
				(width 0.1)
				(type default)
			)
			(layer "F.Fab")
		)
		(fp_line
			(start -0.299974 -0.150114)
			(end 0.299974 -0.150114)
			(stroke
				(width 0.1)
				(type default)
			)
			(layer "F.Fab")
		)
		(fp_line
			(start 0.299974 -0.150114)
			(end 0.299974 0.150114)
			(stroke
				(width 0.1)
				(type default)
			)
			(layer "F.Fab")
		)
		(pad "1" smd rect
			(at -0.2667 0 270)
			(size 0.3048 0.381)
			(layers "F.Cu" "F.Mask" "F.Paste")
			(net "P5E_CPU0_P0_TX_BUF_C_DN<15>")
		)
		(pad "2" smd rect
			(at 0.2667 0 270)
			(size 0.3048 0.381)
			(layers "F.Cu" "F.Mask" "F.Paste")
			(net "P5E_CPU0_P0_TX_BUF_DN<15>")
		)
	)
	(footprint ""
		(layer "F.Cu")
		(at 14.892782 -404.341584 90)
		(property "Reference" "R658"
			(at 0 0 90)
			(layer "F.SilkS")
			(hide yes)
			(effects
				(font
					(size 1.27 1.27)
				)
			)
		)
		(property "Value" ""
			(at 0 0 90)
			(layer "F.Fab")
			(effects
				(font
					(size 1.27 1.27)
				)
			)
		)
		(duplicate_pad_numbers_are_jumpers no)
		(fp_line
			(start 0.7874 -0.4064)
			(end 0.7874 0.4064)
			(stroke
				(width 0.1524)
				(type default)
			)
			(layer "F.SilkS")
		)
		(fp_line
			(start -0.7874 -0.4064)
			(end 0.7874 -0.4064)
			(stroke
				(width 0.1524)
				(type default)
			)
			(layer "F.SilkS")
		)
		(fp_line
			(start 0.7874 0.4064)
			(end -0.7874 0.4064)
			(stroke
				(width 0.1524)
				(type default)
			)
			(layer "F.SilkS")
		)
		(fp_line
			(start -0.7874 0.4064)
			(end -0.7874 -0.4064)
			(stroke
				(width 0.1524)
				(type default)
			)
			(layer "F.SilkS")
		)
		(fp_line
			(start -0.12065 -0.305054)
			(end -0.12065 -0.2794)
			(stroke
				(width 0.1)
				(type default)
			)
			(layer "F.Fab")
		)
		(fp_line
			(start -0.67945 -0.305054)
			(end -0.12065 -0.305054)
			(stroke
				(width 0.1)
				(type default)
			)
			(layer "F.Fab")
		)
		(fp_line
			(start 0.67945 -0.3048)
			(end 0.67945 0.3048)
			(stroke
				(width 0.1)
				(type default)
			)
			(layer "F.Fab")
		)
		(fp_line
			(start 0.12065 -0.3048)
			(end 0.67945 -0.3048)
			(stroke
				(width 0.1)
				(type default)
			)
			(layer "F.Fab")
		)
		(fp_line
			(start 0.12065 -0.2794)
			(end 0.12065 -0.3048)
			(stroke
				(width 0.1)
				(type default)
			)
			(layer "F.Fab")
		)
		(fp_line
			(start -0.12065 -0.2794)
			(end 0.12065 -0.2794)
			(stroke
				(width 0.1)
				(type default)
			)
			(layer "F.Fab")
		)
		(fp_line
			(start 0.120396 0.2794)
			(end -0.12065 0.2794)
			(stroke
				(width 0.1)
				(type default)
			)
			(layer "F.Fab")
		)
		(fp_line
			(start -0.12065 0.2794)
			(end -0.12065 0.3048)
			(stroke
				(width 0.1)
				(type default)
			)
			(layer "F.Fab")
		)
		(fp_line
			(start 0.67945 0.3048)
			(end 0.120396 0.3048)
			(stroke
				(width 0.1)
				(type default)
			)
			(layer "F.Fab")
		)
		(fp_line
			(start 0.120396 0.3048)
			(end 0.120396 0.2794)
			(stroke
				(width 0.1)
				(type default)
			)
			(layer "F.Fab")
		)
		(fp_line
			(start -0.12065 0.3048)
			(end -0.67945 0.3048)
			(stroke
				(width 0.1)
				(type default)
			)
			(layer "F.Fab")
		)
		(fp_line
			(start -0.67945 0.3048)
			(end -0.67945 -0.305054)
			(stroke
				(width 0.1)
				(type default)
			)
			(layer "F.Fab")
		)
		(pad "1" smd circle
			(at -0.40005 0 90)
			(size 0 0)
			(layers "F.Cu" "F.Mask" "F.Paste")
			(net "P0V9_RETIMER_CPU1_PMSDA")
		)
		(pad "2" smd circle
			(at 0.40005 0 90)
			(size 0 0)
			(layers "F.Cu" "F.Mask" "F.Paste")
			(net "P0V9_RETIMER_CPU1_PMSDA_R")
		)
	)
	(footprint ""
		(layer "F.Cu")
		(at 124.968 -106.172 -90)
		(property "Reference" "U8007"
			(at 2.004314 -3.839972 90)
			(unlocked yes)
			(layer "F.SilkS")
			(effects
				(font
					(size 0.7874 0.5842)
					(thickness 0.1524)
				)
				(justify left)
			)
		)
		(property "Value" ""
			(at 0 0 270)
			(layer "F.Fab")
			(effects
				(font
					(size 1.27 1.27)
				)
			)
		)
		(duplicate_pad_numbers_are_jumpers no)
		(fp_line
			(start -1.868424 1.519936)
			(end 1.868424 1.519936)
			(stroke
				(width 0.1524)
				(type default)
			)
			(layer "F.SilkS")
		)
		(fp_line
			(start 1.868424 1.519936)
			(end 1.868424 -1.519936)
			(stroke
				(width 0.1524)
				(type default)
			)
			(layer "F.SilkS")
		)
		(fp_line
			(start -1.868424 -1.519936)
			(end -1.868424 1.519936)
			(stroke
				(width 0.1524)
				(type default)
			)
			(layer "F.SilkS")
		)
		(fp_line
			(start 1.868424 -1.519936)
			(end -1.868424 -1.519936)
			(stroke
				(width 0.1524)
				(type default)
			)
			(layer "F.SilkS")
		)
		(fp_line
			(start -0.700024 1.519936)
			(end 0.700024 1.519936)
			(stroke
				(width 0.1)
				(type default)
			)
			(layer "F.Fab")
		)
		(fp_line
			(start 0.700024 1.519936)
			(end 0.700024 -1.519936)
			(stroke
				(width 0.1)
				(type default)
			)
			(layer "F.Fab")
		)
		(fp_line
			(start -0.700024 -1.519936)
			(end -0.700024 1.519936)
			(stroke
				(width 0.1)
				(type default)
			)
			(layer "F.Fab")
		)
		(fp_line
			(start 0.700024 -1.519936)
			(end -0.700024 -1.519936)
			(stroke
				(width 0.1)
				(type default)
			)
			(layer "F.Fab")
		)
		(pad "1" smd rect
			(at -1.18491 -0.94996 180)
			(size 0.6096 1.0668)
			(layers "F.Cu" "F.Mask" "F.Paste")
			(net "UV_ADR_P2V5_COMP")
		)
		(pad "2" smd rect
			(at -1.18491 0.94996 180)
			(size 0.6096 1.0668)
			(layers "F.Cu" "F.Mask" "F.Paste")
			(net "GND")
		)
		(pad "3" smd rect
			(at 1.18491 0 180)
			(size 0.6096 1.0668)
			(layers "F.Cu" "F.Mask" "F.Paste")
			(net "Net_10850")
		)
	)
	(footprint ""
		(layer "F.Cu")
		(at 418.636958 -365.883952 180)
		(property "Reference" "R119"
			(at 0 0 180)
			(layer "F.SilkS")
			(hide yes)
			(effects
				(font
					(size 1.27 1.27)
				)
			)
		)
		(property "Value" ""
			(at 0 0 180)
			(layer "F.Fab")
			(effects
				(font
					(size 1.27 1.27)
				)
			)
		)
		(duplicate_pad_numbers_are_jumpers no)
		(fp_line
			(start 0.7874 0.4064)
			(end -0.7874 0.4064)
			(stroke
				(width 0.1524)
				(type default)
			)
			(layer "F.SilkS")
		)
		(fp_line
			(start 0.7874 -0.4064)
			(end 0.7874 0.4064)
			(stroke
				(width 0.1524)
				(type default)
			)
			(layer "F.SilkS")
		)
		(fp_line
			(start -0.7874 0.4064)
			(end -0.7874 -0.4064)
			(stroke
				(width 0.1524)
				(type default)
			)
			(layer "F.SilkS")
		)
		(fp_line
			(start -0.7874 -0.4064)
			(end 0.7874 -0.4064)
			(stroke
				(width 0.1524)
				(type default)
			)
			(layer "F.SilkS")
		)
		(fp_line
			(start 0.67945 0.3048)
			(end 0.120396 0.3048)
			(stroke
				(width 0.1)
				(type default)
			)
			(layer "F.Fab")
		)
		(fp_line
			(start 0.67945 -0.3048)
			(end 0.67945 0.3048)
			(stroke
				(width 0.1)
				(type default)
			)
			(layer "F.Fab")
		)
		(fp_line
			(start 0.12065 -0.2794)
			(end 0.12065 -0.3048)
			(stroke
				(width 0.1)
				(type default)
			)
			(layer "F.Fab")
		)
		(fp_line
			(start 0.12065 -0.3048)
			(end 0.67945 -0.3048)
			(stroke
				(width 0.1)
				(type default)
			)
			(layer "F.Fab")
		)
		(fp_line
			(start 0.120396 0.3048)
			(end 0.120396 0.2794)
			(stroke
				(width 0.1)
				(type default)
			)
			(layer "F.Fab")
		)
		(fp_line
			(start 0.120396 0.2794)
			(end -0.12065 0.2794)
			(stroke
				(width 0.1)
				(type default)
			)
			(layer "F.Fab")
		)
		(fp_line
			(start -0.12065 0.3048)
			(end -0.67945 0.3048)
			(stroke
				(width 0.1)
				(type default)
			)
			(layer "F.Fab")
		)
		(fp_line
			(start -0.12065 0.2794)
			(end -0.12065 0.3048)
			(stroke
				(width 0.1)
				(type default)
			)
			(layer "F.Fab")
		)
		(fp_line
			(start -0.12065 -0.2794)
			(end 0.12065 -0.2794)
			(stroke
				(width 0.1)
				(type default)
			)
			(layer "F.Fab")
		)
		(fp_line
			(start -0.12065 -0.305054)
			(end -0.12065 -0.2794)
			(stroke
				(width 0.1)
				(type default)
			)
			(layer "F.Fab")
		)
		(fp_line
			(start -0.67945 0.3048)
			(end -0.67945 -0.305054)
			(stroke
				(width 0.1)
				(type default)
			)
			(layer "F.Fab")
		)
		(fp_line
			(start -0.67945 -0.305054)
			(end -0.12065 -0.305054)
			(stroke
				(width 0.1)
				(type default)
			)
			(layer "F.Fab")
		)
		(pad "1" smd circle
			(at -0.40005 0 180)
			(size 0 0)
			(layers "F.Cu" "F.Mask" "F.Paste")
			(net "SMB_SCM_2_R6_SDA")
		)
		(pad "2" smd circle
			(at 0.40005 0 180)
			(size 0 0)
			(layers "F.Cu" "F.Mask" "F.Paste")
			(net "PVDD11_S3_P0_PMSDA_R")
		)
	)
	(footprint ""
		(layer "F.Cu")
		(at 450.082666 -400.78787 180)
		(property "Reference" "PR6564"
			(at 0 0 180)
			(layer "F.SilkS")
			(hide yes)
			(effects
				(font
					(size 1.27 1.27)
				)
			)
		)
		(property "Value" ""
			(at 0 0 180)
			(layer "F.Fab")
			(effects
				(font
					(size 1.27 1.27)
				)
			)
		)
		(duplicate_pad_numbers_are_jumpers no)
		(fp_line
			(start 0.7874 0.4064)
			(end -0.7874 0.4064)
			(stroke
				(width 0.1524)
				(type default)
			)
			(layer "F.SilkS")
		)
		(fp_line
			(start 0.7874 -0.4064)
			(end 0.7874 0.4064)
			(stroke
				(width 0.1524)
				(type default)
			)
			(layer "F.SilkS")
		)
		(fp_line
			(start -0.233934 -0.4064)
			(end 0.7874 -0.4064)
			(stroke
				(width 0.1524)
				(type default)
			)
			(layer "F.SilkS")
		)
		(fp_line
			(start -0.7874 0.4064)
			(end -0.7874 -0.07747)
			(stroke
				(width 0.1524)
				(type default)
			)
			(layer "F.SilkS")
		)
		(fp_line
			(start 0.67945 0.3048)
			(end 0.120396 0.3048)
			(stroke
				(width 0.1)
				(type default)
			)
			(layer "F.Fab")
		)
		(fp_line
			(start 0.67945 -0.3048)
			(end 0.67945 0.3048)
			(stroke
				(width 0.1)
				(type default)
			)
			(layer "F.Fab")
		)
		(fp_line
			(start 0.12065 -0.2794)
			(end 0.12065 -0.3048)
			(stroke
				(width 0.1)
				(type default)
			)
			(layer "F.Fab")
		)
		(fp_line
			(start 0.12065 -0.3048)
			(end 0.67945 -0.3048)
			(stroke
				(width 0.1)
				(type default)
			)
			(layer "F.Fab")
		)
		(fp_line
			(start 0.120396 0.3048)
			(end 0.120396 0.2794)
			(stroke
				(width 0.1)
				(type default)
			)
			(layer "F.Fab")
		)
		(fp_line
			(start 0.120396 0.2794)
			(end -0.12065 0.2794)
			(stroke
				(width 0.1)
				(type default)
			)
			(layer "F.Fab")
		)
		(fp_line
			(start -0.12065 0.3048)
			(end -0.67945 0.3048)
			(stroke
				(width 0.1)
				(type default)
			)
			(layer "F.Fab")
		)
		(fp_line
			(start -0.12065 0.2794)
			(end -0.12065 0.3048)
			(stroke
				(width 0.1)
				(type default)
			)
			(layer "F.Fab")
		)
		(fp_line
			(start -0.12065 -0.2794)
			(end 0.12065 -0.2794)
			(stroke
				(width 0.1)
				(type default)
			)
			(layer "F.Fab")
		)
		(fp_line
			(start -0.12065 -0.305054)
			(end -0.12065 -0.2794)
			(stroke
				(width 0.1)
				(type default)
			)
			(layer "F.Fab")
		)
		(fp_line
			(start -0.67945 0.3048)
			(end -0.67945 -0.305054)
			(stroke
				(width 0.1)
				(type default)
			)
			(layer "F.Fab")
		)
		(fp_line
			(start -0.67945 -0.305054)
			(end -0.12065 -0.305054)
			(stroke
				(width 0.1)
				(type default)
			)
			(layer "F.Fab")
		)
		(pad "1" smd circle
			(at -0.40005 0 180)
			(size 0 0)
			(layers "F.Cu" "F.Mask" "F.Paste")
			(net "P0V9_RETIMER_CPU0_VOS2")
		)
		(pad "2" smd circle
			(at 0.40005 0 180)
			(size 0 0)
			(layers "F.Cu" "F.Mask" "F.Paste")
			(net "P0V9_CPU0_RT_2D")
		)
	)
)
